FILE_TYPE = MULTI_PHYS_TABLE;

PART '74LVC1G07GV'

{========================================================================================}
:VALUE         | PART_TYPE | MATERIAL | PART_NUMBER    = STANDARD | LIFECYCLE      | PART_NUMBER   | JEDEC_TYPE       | DESCRIPTION                        | MANUFTR | MANUF_PN      | RD_CMPLS_LVL | CMPLS_LVL | FROM_PJ    | CLASS | DIP_SMD | DATA                  | EE_CHECK_LIST | FP_ECN            | PSL | CREATOR | STATUS | MSD       | ESD_CDM | ESD_HBM | ESD_MM | PIN_LENGTH_SHORT_PIN | PIN_LENGTH_LONG_PIN | CREATEDAY  ;
{========================================================================================}
 '74LVC1G07GV' | 'SMLF'    | 'IC'     | 'AL1G0007001'(!) = ''       | ''               | 'AL1G0007001' |'SC-74A_2-9X1-5'| 'IC OTHER(5P) 74LVC1G07GV(SOT753)' | 'NXP'   | '74LVC1G07GV' | 'EP(V1)'     | 'EP(V1)'  | 'S3D-ALAN' | 'IC'  | ''      | 'NXP_74LVC1G07GV.pdf' | ''            | '74LVC1G07GV.msg' | ''  | ''      | ''     | 'Level-1' | 'NA'    | '2000V' | '200V' | '0 MILS'             | '0 MILS'            | '20191122'
 '74LVC1G07GV' | 'SMLF'    | 'EMPTY'  | 'AL1G0007001'(!) = ''       | ''               | 'AL1G0007001' |'SC-74A_2-9X1-5'| 'IC OTHER(5P) 74LVC1G07GV(SOT753)' | 'NXP'   | '74LVC1G07GV' | 'EP(V1)'     | 'EP(V1)'  | 'S3D-ALAN' | 'IC'  | ''      | 'NXP_74LVC1G07GV.pdf' | ''            | '74LVC1G07GV.msg' | ''  | ''      | ''     | 'Level-1' | 'NA'    | '2000V' | '200V' | '0 MILS'             | '0 MILS'            | '20191122'

END_PART

END.

